(kicad_pcb
	(version 20260206)
	(generator "pcbnew")
	(generator_version "10.0")
	(general
		(thickness 1.6)
		(legacy_teardrops no)
	)
	(paper "A4")
	(title_block
		(title "dpb — 14545-sa.0730WZS0815.brd")
		(comment 1 "Honey Badger (Wiwynn) / footprints 524-531 of 1066")
	)
	(layers
		(0 "F.Cu" signal "TOP")
		(4 "In1.Cu" signal "L2GND")
		(6 "In2.Cu" signal "L3")
		(8 "In3.Cu" signal "L4VCC")
		(10 "In4.Cu" signal "L5VCC")
		(12 "In5.Cu" signal "L6")
		(14 "In6.Cu" signal "L7GND")
		(2 "B.Cu" signal "BOTTOM")
		(9 "F.Adhes" user "F.Adhesive")
		(11 "B.Adhes" user "B.Adhesive")
		(13 "F.Paste" user "Package Geometry/Pastemask Top")
		(15 "B.Paste" user "Package Geometry/Pastemask Bottom")
		(5 "F.SilkS" user "Ref Des/Silkscreen Top")
		(7 "B.SilkS" user "Ref Des/Silkscreen Bottom")
		(1 "F.Mask" user "Board Geometry/Soldermask Top")
		(3 "B.Mask" user "Board Geometry/Soldermask Bottom")
		(17 "Dwgs.User" user "User.Drawings")
		(19 "Cmts.User" user "User.Comments")
		(21 "Eco1.User" user "User.Eco1")
		(23 "Eco2.User" user "User.Eco2")
		(25 "Edge.Cuts" user "Board Geometry/Outline")
		(27 "Margin" user)
		(31 "F.CrtYd" user "Package Geometry/Place Bound Top")
		(29 "B.CrtYd" user "Package Geometry/Place Bound Bottom")
		(35 "F.Fab" user "Ref Des/Assembly Top")
		(33 "B.Fab" user "Ref Des/Assembly Bottom")
	)
	(footprint ""
		(layer "F.Cu")
		(at 192.786 -90.297 90)
		(property "Reference" "R553"
			(at 0 0 90)
			(layer "F.SilkS")
			(hide yes)
			(effects
				(font
					(size 1.27 1.27)
				)
			)
		)
		(property "Value" "200KR2F-L-GP"
			(at 0.064008 -3.993896 90)
			(unlocked yes)
			(layer "F.Fab")
			(hide yes)
			(effects
				(font
					(size 1.016 1.016)
					(thickness 0.1524)
				)
			)
		)
		(property "Device Type" "R402H16"
			(at 0.064008 -5.517896 90)
			(unlocked yes)
			(layer "F.Fab")
			(hide yes)
			(effects
				(font
					(size 1.016 1.016)
					(thickness 0.1524)
				)
			)
		)
		(duplicate_pad_numbers_are_jumpers no)
		(fp_line
			(start 0.508 -0.9398)
			(end -0.508 -0.9398)
			(stroke
				(width 0.1524)
				(type default)
			)
			(layer "F.SilkS")
		)
		(fp_line
			(start -0.508 -0.9398)
			(end -0.508 0.9398)
			(stroke
				(width 0.1524)
				(type default)
			)
			(layer "F.SilkS")
		)
		(fp_rect
			(start -0.508 0.9398)
			(end 0.508 -0.9398)
			(stroke
				(width 0)
				(type default)
			)
			(fill no)
			(layer "F.CrtYd")
		)
		(fp_rect
			(start -0.508 0.9398)
			(end 0.508 -0.9398)
			(stroke
				(width 0)
				(type default)
			)
			(fill no)
			(layer "F.Fab")
		)
		(pad "1" smd custom
			(at 0 -0.4445 90)
			(size 0.1397 0.1397)
			(layers "F.Cu" "F.Mask" "F.Paste")
			(net "SW_HDD4_R")
			(options
				(clearance outline)
				(anchor circle)
			)
			(primitives
				(gr_poly
					(pts
						(arc
							(start -0.1778 -0.2794)
							(mid -0.249642 -0.249642)
							(end -0.2794 -0.1778)
						)
						(arc
							(start -0.2794 0.1778)
							(mid -0.249642 0.249642)
							(end -0.1778 0.2794)
						)
						(arc
							(start 0.1778 0.2794)
							(mid 0.249642 0.249642)
							(end 0.2794 0.1778)
						)
						(arc
							(start 0.2794 -0.1778)
							(mid 0.249642 -0.249642)
							(end 0.1778 -0.2794)
						)
					)
					(width 0)
					(fill yes)
				)
			)
		)
		(pad "2" smd custom
			(at 0 0.4445 90)
			(size 0.1397 0.1397)
			(layers "F.Cu" "F.Mask" "F.Paste")
			(net "SW_HDD4_N")
			(options
				(clearance outline)
				(anchor circle)
			)
			(primitives
				(gr_poly
					(pts
						(arc
							(start -0.1778 -0.2794)
							(mid -0.249642 -0.249642)
							(end -0.2794 -0.1778)
						)
						(arc
							(start -0.2794 0.1778)
							(mid -0.249642 0.249642)
							(end -0.1778 0.2794)
						)
						(arc
							(start 0.1778 0.2794)
							(mid 0.249642 0.249642)
							(end 0.2794 0.1778)
						)
						(arc
							(start 0.2794 -0.1778)
							(mid 0.249642 -0.249642)
							(end 0.1778 -0.2794)
						)
					)
					(width 0)
					(fill yes)
				)
			)
		)
	)
	(footprint ""
		(layer "F.Cu")
		(at 4.445 -281.686 90)
		(property "Reference" "PC46"
			(at 0 0 90)
			(layer "F.SilkS")
			(hide yes)
			(effects
				(font
					(size 1.27 1.27)
				)
			)
		)
		(property "Value" "SC22U25V5MX-GP"
			(at -0.0762 -6.1214 90)
			(unlocked yes)
			(layer "F.Fab")
			(hide yes)
			(effects
				(font
					(size 1.016 1.016)
					(thickness 0.1524)
				)
			)
		)
		(property "Device Type" "C805H58"
			(at -0.0762 -8.1534 90)
			(unlocked yes)
			(layer "F.Fab")
			(hide yes)
			(effects
				(font
					(size 1.016 1.016)
					(thickness 0.1524)
				)
			)
		)
		(duplicate_pad_numbers_are_jumpers no)
		(fp_line
			(start 0.635 0)
			(end -0.635 0)
			(stroke
				(width 0.508)
				(type default)
			)
			(layer "F.SilkS")
		)
		(fp_rect
			(start -0.9652 1.778)
			(end 0.9652 -1.778)
			(stroke
				(width 0)
				(type default)
			)
			(fill no)
			(layer "F.CrtYd")
		)
		(fp_poly
			(pts
				(xy -0.9652 -1.778) (xy 0.9652 -1.778) (xy 0.9652 1.778) (xy -0.9652 1.778)
			)
			(stroke
				(width 0)
				(type default)
			)
			(fill no)
			(layer "F.Fab")
		)
		(pad "1" smd rect
			(at 0 -0.9652 90)
			(size 1.397 1.143)
			(layers "F.Cu" "F.Mask" "F.Paste")
			(net "P12V")
		)
		(pad "2" smd rect
			(at 0 0.9652 90)
			(size 1.397 1.143)
			(layers "F.Cu" "F.Mask" "F.Paste")
			(net "GND")
		)
	)
	(footprint ""
		(layer "F.Cu")
		(at 42.8244 -106.7562 90)
		(property "Reference" "R290"
			(at 0 0 90)
			(layer "F.SilkS")
			(hide yes)
			(effects
				(font
					(size 1.27 1.27)
				)
			)
		)
		(property "Value" "4K7R2J-2-GP"
			(at 0.064008 -3.993896 90)
			(unlocked yes)
			(layer "F.Fab")
			(hide yes)
			(effects
				(font
					(size 1.016 1.016)
					(thickness 0.1524)
				)
			)
		)
		(property "Device Type" "R402H16"
			(at 0.064008 -5.517896 90)
			(unlocked yes)
			(layer "F.Fab")
			(hide yes)
			(effects
				(font
					(size 1.016 1.016)
					(thickness 0.1524)
				)
			)
		)
		(duplicate_pad_numbers_are_jumpers no)
		(fp_line
			(start 0.508 -0.9398)
			(end -0.508 -0.9398)
			(stroke
				(width 0.1524)
				(type default)
			)
			(layer "F.SilkS")
		)
		(fp_line
			(start -0.508 -0.9398)
			(end -0.508 0.9398)
			(stroke
				(width 0.1524)
				(type default)
			)
			(layer "F.SilkS")
		)
		(fp_rect
			(start -0.508 0.9398)
			(end 0.508 -0.9398)
			(stroke
				(width 0)
				(type default)
			)
			(fill no)
			(layer "F.CrtYd")
		)
		(fp_rect
			(start -0.508 0.9398)
			(end 0.508 -0.9398)
			(stroke
				(width 0)
				(type default)
			)
			(fill no)
			(layer "F.Fab")
		)
		(pad "1" smd custom
			(at 0 -0.4445 90)
			(size 0.1397 0.1397)
			(layers "F.Cu" "F.Mask" "F.Paste")
			(net "P12V")
			(options
				(clearance outline)
				(anchor circle)
			)
			(primitives
				(gr_poly
					(pts
						(arc
							(start -0.1778 -0.2794)
							(mid -0.249642 -0.249642)
							(end -0.2794 -0.1778)
						)
						(arc
							(start -0.2794 0.1778)
							(mid -0.249642 0.249642)
							(end -0.1778 0.2794)
						)
						(arc
							(start 0.1778 0.2794)
							(mid 0.249642 0.249642)
							(end 0.2794 0.1778)
						)
						(arc
							(start 0.2794 -0.1778)
							(mid 0.249642 -0.249642)
							(end 0.1778 -0.2794)
						)
					)
					(width 0)
					(fill yes)
				)
			)
		)
		(pad "2" smd custom
			(at 0 0.4445 90)
			(size 0.1397 0.1397)
			(layers "F.Cu" "F.Mask" "F.Paste")
			(net "SW_HDD13_R")
			(options
				(clearance outline)
				(anchor circle)
			)
			(primitives
				(gr_poly
					(pts
						(arc
							(start -0.1778 -0.2794)
							(mid -0.249642 -0.249642)
							(end -0.2794 -0.1778)
						)
						(arc
							(start -0.2794 0.1778)
							(mid -0.249642 0.249642)
							(end -0.1778 0.2794)
						)
						(arc
							(start 0.1778 0.2794)
							(mid 0.249642 0.249642)
							(end 0.2794 0.1778)
						)
						(arc
							(start 0.2794 -0.1778)
							(mid 0.249642 -0.249642)
							(end 0.1778 -0.2794)
						)
					)
					(width 0)
					(fill yes)
				)
			)
		)
	)
	(footprint ""
		(layer "F.Cu")
		(at 217.757756 -489.105702 180)
		(property "Reference" "C106"
			(at 0 0 180)
			(layer "F.SilkS")
			(hide yes)
			(effects
				(font
					(size 1.27 1.27)
				)
			)
		)
		(property "Value" "SC1U16V3KX-5GP"
			(at 0 -2.8194 180)
			(unlocked yes)
			(layer "F.Fab")
			(hide yes)
			(effects
				(font
					(size 1.016 1.016)
					(thickness 0.1524)
				)
			)
		)
		(property "Device Type" "C603H36"
			(at 0 -4.3434 180)
			(unlocked yes)
			(layer "F.Fab")
			(hide yes)
			(effects
				(font
					(size 1.016 1.016)
					(thickness 0.1524)
				)
			)
		)
		(duplicate_pad_numbers_are_jumpers no)
		(fp_line
			(start 0.508 0)
			(end -0.508 0)
			(stroke
				(width 0.2032)
				(type default)
			)
			(layer "F.SilkS")
		)
		(fp_rect
			(start -0.5842 1.3335)
			(end 0.5842 -1.3335)
			(stroke
				(width 0)
				(type default)
			)
			(fill no)
			(layer "F.CrtYd")
		)
		(fp_rect
			(start -0.5842 1.3335)
			(end 0.5842 -1.3335)
			(stroke
				(width 0)
				(type default)
			)
			(fill no)
			(layer "F.Fab")
		)
		(pad "1" smd custom
			(at 0 -0.762 180)
			(size 0.2159 0.2159)
			(layers "F.Cu" "F.Mask" "F.Paste")
			(net "P5V_HDD0")
			(options
				(clearance outline)
				(anchor circle)
			)
			(primitives
				(gr_poly
					(pts
						(arc
							(start -0.3302 -0.4318)
							(mid -0.402042 -0.402042)
							(end -0.4318 -0.3302)
						)
						(arc
							(start -0.4318 0.3302)
							(mid -0.402042 0.402042)
							(end -0.3302 0.4318)
						)
						(arc
							(start 0.3302 0.4318)
							(mid 0.402042 0.402042)
							(end 0.4318 0.3302)
						)
						(arc
							(start 0.4318 -0.3302)
							(mid 0.402042 -0.402042)
							(end 0.3302 -0.4318)
						)
					)
					(width 0)
					(fill yes)
				)
			)
		)
		(pad "2" smd custom
			(at 0 0.762 180)
			(size 0.2159 0.2159)
			(layers "F.Cu" "F.Mask" "F.Paste")
			(net "GND")
			(options
				(clearance outline)
				(anchor circle)
			)
			(primitives
				(gr_poly
					(pts
						(arc
							(start -0.3302 -0.4318)
							(mid -0.402042 -0.402042)
							(end -0.4318 -0.3302)
						)
						(arc
							(start -0.4318 0.3302)
							(mid -0.402042 0.402042)
							(end -0.3302 0.4318)
						)
						(arc
							(start 0.3302 0.4318)
							(mid 0.402042 0.402042)
							(end 0.4318 0.3302)
						)
						(arc
							(start 0.4318 -0.3302)
							(mid 0.402042 -0.402042)
							(end 0.3302 -0.4318)
						)
					)
					(width 0)
					(fill yes)
				)
			)
		)
	)
	(footprint ""
		(layer "F.Cu")
		(at 27.812746 -308.257702 180)
		(property "Reference" "U36"
			(at 0 0 180)
			(layer "F.SilkS")
			(hide yes)
			(effects
				(font
					(size 1.27 1.27)
				)
			)
		)
		(property "Value" "74LVC1G08GW-1-GP"
			(at -2.3368 -8.6868 180)
			(unlocked yes)
			(layer "F.Fab")
			(hide yes)
			(effects
				(font
					(size 1.016 1.016)
					(thickness 0.1524)
				)
			)
		)
		(property "Device Type" "SC70-5H44"
			(at -2.3114 -10.414 180)
			(unlocked yes)
			(layer "F.Fab")
			(hide yes)
			(effects
				(font
					(size 1.016 1.016)
					(thickness 0.1524)
				)
			)
		)
		(duplicate_pad_numbers_are_jumpers no)
		(fp_line
			(start 1.3843 -1.8034)
			(end 1.3843 -1.1176)
			(stroke
				(width 0.3302)
				(type default)
			)
			(layer "F.SilkS")
		)
		(fp_line
			(start 1.27 1.7018)
			(end -1.27 1.7018)
			(stroke
				(width 0.1524)
				(type default)
			)
			(layer "F.SilkS")
		)
		(fp_line
			(start 1.27 -1.7018)
			(end 1.27 1.7018)
			(stroke
				(width 0.1524)
				(type default)
			)
			(layer "F.SilkS")
		)
		(fp_line
			(start 0.6604 -1.8034)
			(end 1.3843 -1.8034)
			(stroke
				(width 0.3302)
				(type default)
			)
			(layer "F.SilkS")
		)
		(fp_line
			(start -1.27 1.7018)
			(end -1.27 -1.7018)
			(stroke
				(width 0.1524)
				(type default)
			)
			(layer "F.SilkS")
		)
		(fp_line
			(start -1.27 -1.7018)
			(end 1.27 -1.7018)
			(stroke
				(width 0.1524)
				(type default)
			)
			(layer "F.SilkS")
		)
		(fp_rect
			(start -1.524 1.9558)
			(end 1.524 -1.9558)
			(stroke
				(width 0)
				(type default)
			)
			(fill no)
			(layer "F.CrtYd")
		)
		(fp_poly
			(pts
				(xy -1.524 -1.9558) (xy 1.524 -1.9558) (xy 1.524 1.9558) (xy -1.524 1.9558)
			)
			(stroke
				(width 0)
				(type default)
			)
			(fill no)
			(layer "F.Fab")
		)
		(pad "1" smd rect
			(at 0.65024 -0.8255 180)
			(size 0.4064 1.2192)
			(layers "F.Cu" "F.Mask" "F.Paste")
			(net "SAS_EXP_B_PWR11")
		)
		(pad "2" smd rect
			(at 0 -0.8255 180)
			(size 0.4064 1.2192)
			(layers "F.Cu" "F.Mask" "F.Paste")
			(net "SAS_EXP_A_PWR11")
		)
		(pad "3" smd rect
			(at -0.65024 -0.8255 180)
			(size 0.4064 1.2192)
			(layers "F.Cu" "F.Mask" "F.Paste")
			(net "GND")
		)
		(pad "4" smd rect
			(at -0.65024 0.8255 180)
			(size 0.4064 1.2192)
			(layers "F.Cu" "F.Mask" "F.Paste")
			(net "DRIVE_PWR11")
		)
		(pad "5" smd rect
			(at 0.65024 0.8255 180)
			(size 0.4064 1.2192)
			(layers "F.Cu" "F.Mask" "F.Paste")
			(net "P3V3")
		)
	)
	(footprint ""
		(layer "F.Cu")
		(at 27.634946 -417.452302)
		(property "Reference" "C275"
			(at 0 0 0)
			(layer "F.SilkS")
			(hide yes)
			(effects
				(font
					(size 1.27 1.27)
				)
			)
		)
		(property "Value" "SC10U25V6KX-1GP"
			(at -0.0762 -5.1308 0)
			(unlocked yes)
			(layer "F.Fab")
			(hide yes)
			(effects
				(font
					(size 1.016 1.016)
					(thickness 0.1524)
				)
			)
		)
		(property "Device Type" "C1206H71"
			(at -0.127 -6.6548 0)
			(unlocked yes)
			(layer "F.Fab")
			(hide yes)
			(effects
				(font
					(size 1.016 1.016)
					(thickness 0.1524)
				)
			)
		)
		(duplicate_pad_numbers_are_jumpers no)
		(fp_line
			(start -1.016 -2.2352)
			(end 1.016 -2.2352)
			(stroke
				(width 0.1524)
				(type default)
			)
			(layer "F.SilkS")
		)
		(fp_line
			(start -1.016 -0.8382)
			(end -1.016 -2.2352)
			(stroke
				(width 0.1524)
				(type default)
			)
			(layer "F.SilkS")
		)
		(fp_line
			(start -1.016 2.2352)
			(end -1.016 0.8382)
			(stroke
				(width 0.1524)
				(type default)
			)
			(layer "F.SilkS")
		)
		(fp_line
			(start 1.016 -2.2352)
			(end 1.016 -0.8382)
			(stroke
				(width 0.1524)
				(type default)
			)
			(layer "F.SilkS")
		)
		(fp_line
			(start 1.016 0.8382)
			(end 1.016 2.2352)
			(stroke
				(width 0.1524)
				(type default)
			)
			(layer "F.SilkS")
		)
		(fp_line
			(start 1.016 2.2352)
			(end -1.016 2.2352)
			(stroke
				(width 0.1524)
				(type default)
			)
			(layer "F.SilkS")
		)
		(fp_rect
			(start -1.0922 2.3114)
			(end 1.0922 -2.3114)
			(stroke
				(width 0)
				(type default)
			)
			(fill no)
			(layer "F.CrtYd")
		)
		(fp_poly
			(pts
				(xy 1.0922 -2.3114) (xy 1.0922 2.3114) (xy -1.0922 2.3114) (xy -1.0922 -2.3114)
			)
			(stroke
				(width 0)
				(type default)
			)
			(fill no)
			(layer "F.Fab")
		)
		(pad "1" smd rect
			(at 0 -1.397)
			(size 1.651 1.27)
			(layers "F.Cu" "F.Mask" "F.Paste")
			(net "P12V_HDD10")
		)
		(pad "2" smd rect
			(at 0 1.397)
			(size 1.651 1.27)
			(layers "F.Cu" "F.Mask" "F.Paste")
			(net "GND")
		)
	)
	(footprint ""
		(layer "F.Cu")
		(at 43.179746 -217.706702)
		(property "Reference" "C306"
			(at 0 0 0)
			(layer "F.SilkS")
			(hide yes)
			(effects
				(font
					(size 1.27 1.27)
				)
			)
		)
		(property "Value" "SC10U25V6KX-1GP"
			(at -0.0762 -5.1308 0)
			(unlocked yes)
			(layer "F.Fab")
			(hide yes)
			(effects
				(font
					(size 1.016 1.016)
					(thickness 0.1524)
				)
			)
		)
		(property "Device Type" "C1206H71"
			(at -0.127 -6.6548 0)
			(unlocked yes)
			(layer "F.Fab")
			(hide yes)
			(effects
				(font
					(size 1.016 1.016)
					(thickness 0.1524)
				)
			)
		)
		(duplicate_pad_numbers_are_jumpers no)
		(fp_line
			(start -1.016 -2.2352)
			(end 1.016 -2.2352)
			(stroke
				(width 0.1524)
				(type default)
			)
			(layer "F.SilkS")
		)
		(fp_line
			(start -1.016 -0.8382)
			(end -1.016 -2.2352)
			(stroke
				(width 0.1524)
				(type default)
			)
			(layer "F.SilkS")
		)
		(fp_line
			(start -1.016 2.2352)
			(end -1.016 0.8382)
			(stroke
				(width 0.1524)
				(type default)
			)
			(layer "F.SilkS")
		)
		(fp_line
			(start 1.016 -2.2352)
			(end 1.016 -0.8382)
			(stroke
				(width 0.1524)
				(type default)
			)
			(layer "F.SilkS")
		)
		(fp_line
			(start 1.016 0.8382)
			(end 1.016 2.2352)
			(stroke
				(width 0.1524)
				(type default)
			)
			(layer "F.SilkS")
		)
		(fp_line
			(start 1.016 2.2352)
			(end -1.016 2.2352)
			(stroke
				(width 0.1524)
				(type default)
			)
			(layer "F.SilkS")
		)
		(fp_rect
			(start -1.0922 2.3114)
			(end 1.0922 -2.3114)
			(stroke
				(width 0)
				(type default)
			)
			(fill no)
			(layer "F.CrtYd")
		)
		(fp_poly
			(pts
				(xy 1.0922 -2.3114) (xy 1.0922 2.3114) (xy -1.0922 2.3114) (xy -1.0922 -2.3114)
			)
			(stroke
				(width 0)
				(type default)
			)
			(fill no)
			(layer "F.Fab")
		)
		(pad "1" smd rect
			(at 0 -1.397)
			(size 1.651 1.27)
			(layers "F.Cu" "F.Mask" "F.Paste")
			(net "P12V_HDD12")
		)
		(pad "2" smd rect
			(at 0 1.397)
			(size 1.651 1.27)
			(layers "F.Cu" "F.Mask" "F.Paste")
			(net "GND")
		)
	)
	(footprint ""
		(layer "F.Cu")
		(at 102.234746 -14.2367 90)
		(property "Reference" "R305"
			(at 0 0 90)
			(layer "F.SilkS")
			(hide yes)
			(effects
				(font
					(size 1.27 1.27)
				)
			)
		)
		(property "Value" "1KR2F-3-GP"
			(at 0.064008 -3.993896 90)
			(unlocked yes)
			(layer "F.Fab")
			(hide yes)
			(effects
				(font
					(size 1.016 1.016)
					(thickness 0.1524)
				)
			)
		)
		(property "Device Type" "R402H16"
			(at 0.064008 -5.517896 90)
			(unlocked yes)
			(layer "F.Fab")
			(hide yes)
			(effects
				(font
					(size 1.016 1.016)
					(thickness 0.1524)
				)
			)
		)
		(duplicate_pad_numbers_are_jumpers no)
		(fp_line
			(start 0.508 -0.9398)
			(end -0.508 -0.9398)
			(stroke
				(width 0.1524)
				(type default)
			)
			(layer "F.SilkS")
		)
		(fp_line
			(start -0.508 -0.9398)
			(end -0.508 0.9398)
			(stroke
				(width 0.1524)
				(type default)
			)
			(layer "F.SilkS")
		)
		(fp_rect
			(start -0.508 0.9398)
			(end 0.508 -0.9398)
			(stroke
				(width 0)
				(type default)
			)
			(fill no)
			(layer "F.CrtYd")
		)
		(fp_rect
			(start -0.508 0.9398)
			(end 0.508 -0.9398)
			(stroke
				(width 0)
				(type default)
			)
			(fill no)
			(layer "F.Fab")
		)
		(pad "1" smd custom
			(at 0 -0.4445 90)
			(size 0.1397 0.1397)
			(layers "F.Cu" "F.Mask" "F.Paste")
			(net "P3V3")
			(options
				(clearance outline)
				(anchor circle)
			)
			(primitives
				(gr_poly
					(pts
						(arc
							(start -0.1778 -0.2794)
							(mid -0.249642 -0.249642)
							(end -0.2794 -0.1778)
						)
						(arc
							(start -0.2794 0.1778)
							(mid -0.249642 0.249642)
							(end -0.1778 0.2794)
						)
						(arc
							(start 0.1778 0.2794)
							(mid 0.249642 0.249642)
							(end 0.2794 0.1778)
						)
						(arc
							(start 0.2794 -0.1778)
							(mid 0.249642 -0.249642)
							(end 0.1778 -0.2794)
						)
					)
					(width 0)
					(fill yes)
				)
			)
		)
		(pad "2" smd custom
			(at 0 0.4445 90)
			(size 0.1397 0.1397)
			(layers "F.Cu" "F.Mask" "F.Paste")
			(net "SW_PWR_HDD14")
			(options
				(clearance outline)
				(anchor circle)
			)
			(primitives
				(gr_poly
					(pts
						(arc
							(start -0.1778 -0.2794)
							(mid -0.249642 -0.249642)
							(end -0.2794 -0.1778)
						)
						(arc
							(start -0.2794 0.1778)
							(mid -0.249642 0.249642)
							(end -0.1778 0.2794)
						)
						(arc
							(start 0.1778 0.2794)
							(mid 0.249642 0.249642)
							(end 0.2794 0.1778)
						)
						(arc
							(start 0.2794 -0.1778)
							(mid 0.249642 -0.249642)
							(end 0.1778 -0.2794)
						)
					)
					(width 0)
					(fill yes)
				)
			)
		)
	)
)
